(kicad_pcb
	(version 20260206)
	(generator "pcbnew")
	(generator_version "10.0")
	(general
		(thickness 1.6)
		(legacy_teardrops no)
	)
	(paper "A4")
	(title_block
		(title "12092022_DA0F0TFB6D0_F0T_FAN_BOARD_MP5048_D_brd_v02_OCP.brd")
		(comment 1 "Grand Teton / footprints 428-434 of 924")
	)
	(layers
		(0 "F.Cu" signal "TOP")
		(4 "In1.Cu" signal "GND")
		(6 "In2.Cu" signal "IN1")
		(8 "In3.Cu" signal "IN2")
		(10 "In4.Cu" signal "GND1")
		(2 "B.Cu" signal "BOTTOM")
		(9 "F.Adhes" user "F.Adhesive")
		(11 "B.Adhes" user "B.Adhesive")
		(13 "F.Paste" user "Package Geometry/Pastemask Top")
		(15 "B.Paste" user "Package Geometry/Pastemask Bottom")
		(5 "F.SilkS" user "Ref Des/Silkscreen Top")
		(7 "B.SilkS" user "Ref Des/Silkscreen Bottom")
		(1 "F.Mask" user "Board Geometry/Soldermask Top")
		(3 "B.Mask" user "Board Geometry/Soldermask Bottom")
		(17 "Dwgs.User" user "User.Drawings")
		(19 "Cmts.User" user "User.Comments")
		(21 "Eco1.User" user "User.Eco1")
		(23 "Eco2.User" user "User.Eco2")
		(25 "Edge.Cuts" user "Board Geometry/Outline")
		(27 "Margin" user)
		(31 "F.CrtYd" user "Package Geometry/Place Bound Top")
		(29 "B.CrtYd" user "Package Geometry/Place Bound Bottom")
		(35 "F.Fab" user "Ref Des/Assembly Top")
		(33 "B.Fab" user "Ref Des/Assembly Bottom")
	)
	(footprint ""
		(layer "F.Cu")
		(at 12.94892 -313.74588)
		(property "Reference" "ME3"
			(at 0 0 0)
			(layer "F.SilkS")
			(hide yes)
			(effects
				(font
					(size 1.27 1.27)
				)
			)
		)
		(property "Value" ""
			(at 0 0 0)
			(layer "F.Fab")
			(effects
				(font
					(size 1.27 1.27)
				)
			)
		)
		(duplicate_pad_numbers_are_jumpers no)
	)
	(footprint ""
		(layer "F.Cu")
		(at 18.415 -183.896 180)
		(property "Reference" "R5466"
			(at 0 0 180)
			(layer "F.SilkS")
			(hide yes)
			(effects
				(font
					(size 1.27 1.27)
				)
			)
		)
		(property "Value" ""
			(at 0 0 180)
			(layer "F.Fab")
			(effects
				(font
					(size 1.27 1.27)
				)
			)
		)
		(duplicate_pad_numbers_are_jumpers no)
		(fp_line
			(start 0.7874 0.4064)
			(end -0.7874 0.4064)
			(stroke
				(width 0.1524)
				(type default)
			)
			(layer "F.SilkS")
		)
		(fp_line
			(start 0.7874 -0.4064)
			(end 0.7874 0.4064)
			(stroke
				(width 0.1524)
				(type default)
			)
			(layer "F.SilkS")
		)
		(fp_line
			(start -0.7874 0.4064)
			(end -0.7874 -0.4064)
			(stroke
				(width 0.1524)
				(type default)
			)
			(layer "F.SilkS")
		)
		(fp_line
			(start -0.7874 -0.4064)
			(end 0.7874 -0.4064)
			(stroke
				(width 0.1524)
				(type default)
			)
			(layer "F.SilkS")
		)
		(fp_line
			(start 0.67945 0.3048)
			(end 0.120396 0.3048)
			(stroke
				(width 0.1)
				(type default)
			)
			(layer "F.Fab")
		)
		(fp_line
			(start 0.67945 -0.3048)
			(end 0.67945 0.3048)
			(stroke
				(width 0.1)
				(type default)
			)
			(layer "F.Fab")
		)
		(fp_line
			(start 0.12065 -0.2794)
			(end 0.12065 -0.3048)
			(stroke
				(width 0.1)
				(type default)
			)
			(layer "F.Fab")
		)
		(fp_line
			(start 0.12065 -0.3048)
			(end 0.67945 -0.3048)
			(stroke
				(width 0.1)
				(type default)
			)
			(layer "F.Fab")
		)
		(fp_line
			(start 0.120396 0.3048)
			(end 0.120396 0.2794)
			(stroke
				(width 0.1)
				(type default)
			)
			(layer "F.Fab")
		)
		(fp_line
			(start 0.120396 0.2794)
			(end -0.12065 0.2794)
			(stroke
				(width 0.1)
				(type default)
			)
			(layer "F.Fab")
		)
		(fp_line
			(start -0.12065 0.3048)
			(end -0.67945 0.3048)
			(stroke
				(width 0.1)
				(type default)
			)
			(layer "F.Fab")
		)
		(fp_line
			(start -0.12065 0.2794)
			(end -0.12065 0.3048)
			(stroke
				(width 0.1)
				(type default)
			)
			(layer "F.Fab")
		)
		(fp_line
			(start -0.12065 -0.2794)
			(end 0.12065 -0.2794)
			(stroke
				(width 0.1)
				(type default)
			)
			(layer "F.Fab")
		)
		(fp_line
			(start -0.12065 -0.305054)
			(end -0.12065 -0.2794)
			(stroke
				(width 0.1)
				(type default)
			)
			(layer "F.Fab")
		)
		(fp_line
			(start -0.67945 0.3048)
			(end -0.67945 -0.305054)
			(stroke
				(width 0.1)
				(type default)
			)
			(layer "F.Fab")
		)
		(fp_line
			(start -0.67945 -0.305054)
			(end -0.12065 -0.305054)
			(stroke
				(width 0.1)
				(type default)
			)
			(layer "F.Fab")
		)
		(pad "1" smd circle
			(at -0.40005 0 180)
			(size 0 0)
			(layers "F.Cu" "F.Mask" "F.Paste")
			(net "SMB_PDBV_FAN_SDA")
		)
		(pad "2" smd circle
			(at 0.40005 0 180)
			(size 0 0)
			(layers "F.Cu" "F.Mask" "F.Paste")
			(net "SMB_PDBV_FAN_R_IOX_SDA")
		)
	)
	(footprint ""
		(layer "F.Cu")
		(at 6.604 -123.698)
		(property "Reference" "R5702"
			(at 0 0 0)
			(layer "F.SilkS")
			(hide yes)
			(effects
				(font
					(size 1.27 1.27)
				)
			)
		)
		(property "Value" ""
			(at 0 0 0)
			(layer "F.Fab")
			(effects
				(font
					(size 1.27 1.27)
				)
			)
		)
		(duplicate_pad_numbers_are_jumpers no)
		(fp_line
			(start -0.7874 -0.4064)
			(end 0.7874 -0.4064)
			(stroke
				(width 0.1524)
				(type default)
			)
			(layer "F.SilkS")
		)
		(fp_line
			(start -0.7874 0.4064)
			(end -0.7874 -0.4064)
			(stroke
				(width 0.1524)
				(type default)
			)
			(layer "F.SilkS")
		)
		(fp_line
			(start 0.7874 -0.4064)
			(end 0.7874 0.4064)
			(stroke
				(width 0.1524)
				(type default)
			)
			(layer "F.SilkS")
		)
		(fp_line
			(start 0.7874 0.4064)
			(end -0.7874 0.4064)
			(stroke
				(width 0.1524)
				(type default)
			)
			(layer "F.SilkS")
		)
		(fp_line
			(start -0.67945 -0.305054)
			(end -0.12065 -0.305054)
			(stroke
				(width 0.1)
				(type default)
			)
			(layer "F.Fab")
		)
		(fp_line
			(start -0.67945 0.3048)
			(end -0.67945 -0.305054)
			(stroke
				(width 0.1)
				(type default)
			)
			(layer "F.Fab")
		)
		(fp_line
			(start -0.12065 -0.305054)
			(end -0.12065 -0.2794)
			(stroke
				(width 0.1)
				(type default)
			)
			(layer "F.Fab")
		)
		(fp_line
			(start -0.12065 -0.2794)
			(end 0.12065 -0.2794)
			(stroke
				(width 0.1)
				(type default)
			)
			(layer "F.Fab")
		)
		(fp_line
			(start -0.12065 0.2794)
			(end -0.12065 0.3048)
			(stroke
				(width 0.1)
				(type default)
			)
			(layer "F.Fab")
		)
		(fp_line
			(start -0.12065 0.3048)
			(end -0.67945 0.3048)
			(stroke
				(width 0.1)
				(type default)
			)
			(layer "F.Fab")
		)
		(fp_line
			(start 0.120396 0.2794)
			(end -0.12065 0.2794)
			(stroke
				(width 0.1)
				(type default)
			)
			(layer "F.Fab")
		)
		(fp_line
			(start 0.120396 0.3048)
			(end 0.120396 0.2794)
			(stroke
				(width 0.1)
				(type default)
			)
			(layer "F.Fab")
		)
		(fp_line
			(start 0.12065 -0.3048)
			(end 0.67945 -0.3048)
			(stroke
				(width 0.1)
				(type default)
			)
			(layer "F.Fab")
		)
		(fp_line
			(start 0.12065 -0.2794)
			(end 0.12065 -0.3048)
			(stroke
				(width 0.1)
				(type default)
			)
			(layer "F.Fab")
		)
		(fp_line
			(start 0.67945 -0.3048)
			(end 0.67945 0.3048)
			(stroke
				(width 0.1)
				(type default)
			)
			(layer "F.Fab")
		)
		(fp_line
			(start 0.67945 0.3048)
			(end 0.120396 0.3048)
			(stroke
				(width 0.1)
				(type default)
			)
			(layer "F.Fab")
		)
		(pad "1" smd rect
			(at -0.40005 0 180)
			(size 0.4572 0.508)
			(layers "F.Cu" "F.Mask" "F.Paste")
			(net "P12V_LED_R_FAN5")
		)
		(pad "2" smd rect
			(at 0.40005 0 180)
			(size 0.4572 0.508)
			(layers "F.Cu" "F.Mask" "F.Paste")
			(net "P12V_LED_R1_FAN5")
		)
	)
	(footprint ""
		(layer "F.Cu")
		(at 6.477 -162.814)
		(property "Reference" "R98"
			(at 0 0 0)
			(layer "F.SilkS")
			(hide yes)
			(effects
				(font
					(size 1.27 1.27)
				)
			)
		)
		(property "Value" ""
			(at 0 0 0)
			(layer "F.Fab")
			(effects
				(font
					(size 1.27 1.27)
				)
			)
		)
		(duplicate_pad_numbers_are_jumpers no)
		(fp_line
			(start -0.7874 -0.4064)
			(end 0.7874 -0.4064)
			(stroke
				(width 0.1524)
				(type default)
			)
			(layer "F.SilkS")
		)
		(fp_line
			(start -0.7874 0.4064)
			(end -0.7874 -0.4064)
			(stroke
				(width 0.1524)
				(type default)
			)
			(layer "F.SilkS")
		)
		(fp_line
			(start 0.7874 -0.4064)
			(end 0.7874 0.4064)
			(stroke
				(width 0.1524)
				(type default)
			)
			(layer "F.SilkS")
		)
		(fp_line
			(start 0.7874 0.4064)
			(end -0.7874 0.4064)
			(stroke
				(width 0.1524)
				(type default)
			)
			(layer "F.SilkS")
		)
		(fp_line
			(start -0.67945 -0.305054)
			(end -0.12065 -0.305054)
			(stroke
				(width 0.1)
				(type default)
			)
			(layer "F.Fab")
		)
		(fp_line
			(start -0.67945 0.3048)
			(end -0.67945 -0.305054)
			(stroke
				(width 0.1)
				(type default)
			)
			(layer "F.Fab")
		)
		(fp_line
			(start -0.12065 -0.305054)
			(end -0.12065 -0.2794)
			(stroke
				(width 0.1)
				(type default)
			)
			(layer "F.Fab")
		)
		(fp_line
			(start -0.12065 -0.2794)
			(end 0.12065 -0.2794)
			(stroke
				(width 0.1)
				(type default)
			)
			(layer "F.Fab")
		)
		(fp_line
			(start -0.12065 0.2794)
			(end -0.12065 0.3048)
			(stroke
				(width 0.1)
				(type default)
			)
			(layer "F.Fab")
		)
		(fp_line
			(start -0.12065 0.3048)
			(end -0.67945 0.3048)
			(stroke
				(width 0.1)
				(type default)
			)
			(layer "F.Fab")
		)
		(fp_line
			(start 0.120396 0.2794)
			(end -0.12065 0.2794)
			(stroke
				(width 0.1)
				(type default)
			)
			(layer "F.Fab")
		)
		(fp_line
			(start 0.120396 0.3048)
			(end 0.120396 0.2794)
			(stroke
				(width 0.1)
				(type default)
			)
			(layer "F.Fab")
		)
		(fp_line
			(start 0.12065 -0.3048)
			(end 0.67945 -0.3048)
			(stroke
				(width 0.1)
				(type default)
			)
			(layer "F.Fab")
		)
		(fp_line
			(start 0.12065 -0.2794)
			(end 0.12065 -0.3048)
			(stroke
				(width 0.1)
				(type default)
			)
			(layer "F.Fab")
		)
		(fp_line
			(start 0.67945 -0.3048)
			(end 0.67945 0.3048)
			(stroke
				(width 0.1)
				(type default)
			)
			(layer "F.Fab")
		)
		(fp_line
			(start 0.67945 0.3048)
			(end 0.120396 0.3048)
			(stroke
				(width 0.1)
				(type default)
			)
			(layer "F.Fab")
		)
		(pad "1" smd circle
			(at -0.40005 0)
			(size 0 0)
			(layers "F.Cu" "F.Mask" "F.Paste")
			(net "P3V3_AUX")
		)
		(pad "2" smd circle
			(at 0.40005 0)
			(size 0 0)
			(layers "F.Cu" "F.Mask" "F.Paste")
			(net "FAN_0_PRSNT_BUF_R_N")
		)
	)
	(footprint ""
		(layer "F.Cu")
		(at 43.561 -170.815)
		(property "Reference" "R5095"
			(at 0 0 0)
			(layer "F.SilkS")
			(hide yes)
			(effects
				(font
					(size 1.27 1.27)
				)
			)
		)
		(property "Value" ""
			(at 0 0 0)
			(layer "F.Fab")
			(effects
				(font
					(size 1.27 1.27)
				)
			)
		)
		(duplicate_pad_numbers_are_jumpers no)
		(fp_line
			(start -0.7874 -0.4064)
			(end 0.7874 -0.4064)
			(stroke
				(width 0.1524)
				(type default)
			)
			(layer "F.SilkS")
		)
		(fp_line
			(start -0.7874 0.4064)
			(end -0.7874 -0.4064)
			(stroke
				(width 0.1524)
				(type default)
			)
			(layer "F.SilkS")
		)
		(fp_line
			(start 0.7874 -0.4064)
			(end 0.7874 0.4064)
			(stroke
				(width 0.1524)
				(type default)
			)
			(layer "F.SilkS")
		)
		(fp_line
			(start 0.7874 0.4064)
			(end -0.7874 0.4064)
			(stroke
				(width 0.1524)
				(type default)
			)
			(layer "F.SilkS")
		)
		(fp_line
			(start -0.67945 -0.305054)
			(end -0.12065 -0.305054)
			(stroke
				(width 0.1)
				(type default)
			)
			(layer "F.Fab")
		)
		(fp_line
			(start -0.67945 0.3048)
			(end -0.67945 -0.305054)
			(stroke
				(width 0.1)
				(type default)
			)
			(layer "F.Fab")
		)
		(fp_line
			(start -0.12065 -0.305054)
			(end -0.12065 -0.2794)
			(stroke
				(width 0.1)
				(type default)
			)
			(layer "F.Fab")
		)
		(fp_line
			(start -0.12065 -0.2794)
			(end 0.12065 -0.2794)
			(stroke
				(width 0.1)
				(type default)
			)
			(layer "F.Fab")
		)
		(fp_line
			(start -0.12065 0.2794)
			(end -0.12065 0.3048)
			(stroke
				(width 0.1)
				(type default)
			)
			(layer "F.Fab")
		)
		(fp_line
			(start -0.12065 0.3048)
			(end -0.67945 0.3048)
			(stroke
				(width 0.1)
				(type default)
			)
			(layer "F.Fab")
		)
		(fp_line
			(start 0.120396 0.2794)
			(end -0.12065 0.2794)
			(stroke
				(width 0.1)
				(type default)
			)
			(layer "F.Fab")
		)
		(fp_line
			(start 0.120396 0.3048)
			(end 0.120396 0.2794)
			(stroke
				(width 0.1)
				(type default)
			)
			(layer "F.Fab")
		)
		(fp_line
			(start 0.12065 -0.3048)
			(end 0.67945 -0.3048)
			(stroke
				(width 0.1)
				(type default)
			)
			(layer "F.Fab")
		)
		(fp_line
			(start 0.12065 -0.2794)
			(end 0.12065 -0.3048)
			(stroke
				(width 0.1)
				(type default)
			)
			(layer "F.Fab")
		)
		(fp_line
			(start 0.67945 -0.3048)
			(end 0.67945 0.3048)
			(stroke
				(width 0.1)
				(type default)
			)
			(layer "F.Fab")
		)
		(fp_line
			(start 0.67945 0.3048)
			(end 0.120396 0.3048)
			(stroke
				(width 0.1)
				(type default)
			)
			(layer "F.Fab")
		)
		(pad "1" smd circle
			(at -0.40005 0)
			(size 0 0)
			(layers "F.Cu" "F.Mask" "F.Paste")
			(net "FAN_0_FAIL_LED")
		)
		(pad "2" smd circle
			(at 0.40005 0)
			(size 0 0)
			(layers "F.Cu" "F.Mask" "F.Paste")
			(net "FAN_0_FAIL_R_LED")
		)
	)
	(footprint ""
		(layer "F.Cu")
		(at 28.956 -174.625 180)
		(property "Reference" "R5105"
			(at 0 0 180)
			(layer "F.SilkS")
			(hide yes)
			(effects
				(font
					(size 1.27 1.27)
				)
			)
		)
		(property "Value" ""
			(at 0 0 180)
			(layer "F.Fab")
			(effects
				(font
					(size 1.27 1.27)
				)
			)
		)
		(duplicate_pad_numbers_are_jumpers no)
		(fp_line
			(start 0.7874 0.4064)
			(end -0.7874 0.4064)
			(stroke
				(width 0.1524)
				(type default)
			)
			(layer "F.SilkS")
		)
		(fp_line
			(start 0.7874 -0.4064)
			(end 0.7874 0.4064)
			(stroke
				(width 0.1524)
				(type default)
			)
			(layer "F.SilkS")
		)
		(fp_line
			(start -0.7874 0.4064)
			(end -0.7874 -0.4064)
			(stroke
				(width 0.1524)
				(type default)
			)
			(layer "F.SilkS")
		)
		(fp_line
			(start -0.7874 -0.4064)
			(end 0.7874 -0.4064)
			(stroke
				(width 0.1524)
				(type default)
			)
			(layer "F.SilkS")
		)
		(fp_line
			(start 0.67945 0.3048)
			(end 0.120396 0.3048)
			(stroke
				(width 0.1)
				(type default)
			)
			(layer "F.Fab")
		)
		(fp_line
			(start 0.67945 -0.3048)
			(end 0.67945 0.3048)
			(stroke
				(width 0.1)
				(type default)
			)
			(layer "F.Fab")
		)
		(fp_line
			(start 0.12065 -0.2794)
			(end 0.12065 -0.3048)
			(stroke
				(width 0.1)
				(type default)
			)
			(layer "F.Fab")
		)
		(fp_line
			(start 0.12065 -0.3048)
			(end 0.67945 -0.3048)
			(stroke
				(width 0.1)
				(type default)
			)
			(layer "F.Fab")
		)
		(fp_line
			(start 0.120396 0.3048)
			(end 0.120396 0.2794)
			(stroke
				(width 0.1)
				(type default)
			)
			(layer "F.Fab")
		)
		(fp_line
			(start 0.120396 0.2794)
			(end -0.12065 0.2794)
			(stroke
				(width 0.1)
				(type default)
			)
			(layer "F.Fab")
		)
		(fp_line
			(start -0.12065 0.3048)
			(end -0.67945 0.3048)
			(stroke
				(width 0.1)
				(type default)
			)
			(layer "F.Fab")
		)
		(fp_line
			(start -0.12065 0.2794)
			(end -0.12065 0.3048)
			(stroke
				(width 0.1)
				(type default)
			)
			(layer "F.Fab")
		)
		(fp_line
			(start -0.12065 -0.2794)
			(end 0.12065 -0.2794)
			(stroke
				(width 0.1)
				(type default)
			)
			(layer "F.Fab")
		)
		(fp_line
			(start -0.12065 -0.305054)
			(end -0.12065 -0.2794)
			(stroke
				(width 0.1)
				(type default)
			)
			(layer "F.Fab")
		)
		(fp_line
			(start -0.67945 0.3048)
			(end -0.67945 -0.305054)
			(stroke
				(width 0.1)
				(type default)
			)
			(layer "F.Fab")
		)
		(fp_line
			(start -0.67945 -0.305054)
			(end -0.12065 -0.305054)
			(stroke
				(width 0.1)
				(type default)
			)
			(layer "F.Fab")
		)
		(pad "1" smd circle
			(at -0.40005 0 180)
			(size 0 0)
			(layers "F.Cu" "F.Mask" "F.Paste")
			(net "FAN_5_FAIL_LED")
		)
		(pad "2" smd circle
			(at 0.40005 0 180)
			(size 0 0)
			(layers "F.Cu" "F.Mask" "F.Paste")
			(net "FAN_5_FAIL_R_LED")
		)
	)
	(footprint ""
		(layer "F.Cu")
		(at 39.206932 -71.812912)
		(property "Reference" "C2069"
			(at 0 0 0)
			(layer "F.SilkS")
			(hide yes)
			(effects
				(font
					(size 1.27 1.27)
				)
			)
		)
		(property "Value" ""
			(at 0 0 0)
			(layer "F.Fab")
			(effects
				(font
					(size 1.27 1.27)
				)
			)
		)
		(duplicate_pad_numbers_are_jumpers no)
		(fp_line
			(start -0.7874 -0.4064)
			(end 0.7874 -0.4064)
			(stroke
				(width 0.1524)
				(type default)
			)
			(layer "F.SilkS")
		)
		(fp_line
			(start -0.7874 0.4064)
			(end -0.7874 -0.4064)
			(stroke
				(width 0.1524)
				(type default)
			)
			(layer "F.SilkS")
		)
		(fp_line
			(start 0.7874 -0.4064)
			(end 0.7874 0.4064)
			(stroke
				(width 0.1524)
				(type default)
			)
			(layer "F.SilkS")
		)
		(fp_line
			(start 0.7874 0.4064)
			(end -0.7874 0.4064)
			(stroke
				(width 0.1524)
				(type default)
			)
			(layer "F.SilkS")
		)
		(fp_line
			(start -0.67945 -0.305054)
			(end -0.12065 -0.305054)
			(stroke
				(width 0.1)
				(type default)
			)
			(layer "F.Fab")
		)
		(fp_line
			(start -0.67945 0.3048)
			(end -0.67945 -0.305054)
			(stroke
				(width 0.1)
				(type default)
			)
			(layer "F.Fab")
		)
		(fp_line
			(start -0.12065 -0.305054)
			(end -0.12065 -0.2794)
			(stroke
				(width 0.1)
				(type default)
			)
			(layer "F.Fab")
		)
		(fp_line
			(start -0.12065 -0.2794)
			(end 0.12065 -0.2794)
			(stroke
				(width 0.1)
				(type default)
			)
			(layer "F.Fab")
		)
		(fp_line
			(start -0.12065 0.2794)
			(end -0.12065 0.3048)
			(stroke
				(width 0.1)
				(type default)
			)
			(layer "F.Fab")
		)
		(fp_line
			(start -0.12065 0.3048)
			(end -0.67945 0.3048)
			(stroke
				(width 0.1)
				(type default)
			)
			(layer "F.Fab")
		)
		(fp_line
			(start 0.120396 0.2794)
			(end -0.12065 0.2794)
			(stroke
				(width 0.1)
				(type default)
			)
			(layer "F.Fab")
		)
		(fp_line
			(start 0.120396 0.3048)
			(end 0.120396 0.2794)
			(stroke
				(width 0.1)
				(type default)
			)
			(layer "F.Fab")
		)
		(fp_line
			(start 0.12065 -0.3048)
			(end 0.67945 -0.3048)
			(stroke
				(width 0.1)
				(type default)
			)
			(layer "F.Fab")
		)
		(fp_line
			(start 0.12065 -0.2794)
			(end 0.12065 -0.3048)
			(stroke
				(width 0.1)
				(type default)
			)
			(layer "F.Fab")
		)
		(fp_line
			(start 0.67945 -0.3048)
			(end 0.67945 0.3048)
			(stroke
				(width 0.1)
				(type default)
			)
			(layer "F.Fab")
		)
		(fp_line
			(start 0.67945 0.3048)
			(end 0.120396 0.3048)
			(stroke
				(width 0.1)
				(type default)
			)
			(layer "F.Fab")
		)
		(pad "1" smd circle
			(at -0.40005 0)
			(size 0 0)
			(layers "F.Cu" "F.Mask" "F.Paste")
			(net "P3V3_AUX")
		)
		(pad "2" smd circle
			(at 0.40005 0)
			(size 0 0)
			(layers "F.Cu" "F.Mask" "F.Paste")
			(net "GND")
		)
	)
)
